(kicad_pcb
	(version 20241229)
	(generator "pcbnew")
	(generator_version "9.0")
	(general
		(thickness 1.61)
		(legacy_teardrops no)
	)
	(paper "A3")
	(title_block
		(title "SO-DIMM DDR5 Tester")
		(date "2025-11-26")
		(rev "1.3.0")
		(comment 9 "footprints 133-138 of 627")
	)
	(layers
		(0 "F.Cu" signal)
		(4 "In1.Cu" power)
		(6 "In2.Cu" mixed)
		(8 "In3.Cu" power)
		(10 "In4.Cu" mixed)
		(12 "In5.Cu" power)
		(14 "In6.Cu" mixed)
		(16 "In7.Cu" power)
		(18 "In8.Cu" power)
		(20 "In9.Cu" mixed)
		(22 "In10.Cu" power)
		(2 "B.Cu" signal)
		(9 "F.Adhes" user "F.Adhesive")
		(11 "B.Adhes" user "B.Adhesive")
		(13 "F.Paste" user)
		(15 "B.Paste" user)
		(5 "F.SilkS" user "F.Silkscreen")
		(7 "B.SilkS" user "B.Silkscreen")
		(1 "F.Mask" user)
		(3 "B.Mask" user)
		(17 "Dwgs.User" user "User.Drawings")
		(19 "Cmts.User" user "User.Comments")
		(21 "Eco1.User" user "User.Eco1")
		(23 "Eco2.User" user "User.Eco2")
		(25 "Edge.Cuts" user)
		(27 "Margin" user)
		(31 "F.CrtYd" user "F.Courtyard")
		(29 "B.CrtYd" user "B.Courtyard")
		(35 "F.Fab" user)
		(33 "B.Fab" user)
	)
	(footprint "antmicro-footprints:Mech_Lightpipe_Mentor_1296.2013"
		(layer "F.Cu")
		(at 76.060501 126.276 90)
		(property "Reference" "H2"
			(at 0 -0.5 180)
			(unlocked yes)
			(layer "F.SilkS")
			(hide yes)
			(effects
				(font
					(size 0.7 0.7)
					(thickness 0.15)
				)
				(justify left bottom)
			)
		)
		(property "Value" "Lightpipe_Mentor_1296.2013"
			(at -1.75 6.25 90)
			(unlocked yes)
			(layer "F.Fab")
			(effects
				(font
					(size 0.7 0.7)
					(thickness 0.15)
				)
				(justify left bottom)
			)
		)
		(property "Datasheet" "https://docs.rs-online.com/e47b/0900766b813f6efb.pdf"
			(at 0 0 90)
			(layer "F.Fab")
			(hide yes)
			(effects
				(font
					(size 1.27 1.27)
					(thickness 0.15)
				)
			)
		)
		(property "Author" "Antmicro"
			(at 202.336501 50.215499 0)
			(layer "F.Fab")
			(hide yes)
			(effects
				(font
					(size 1 1)
					(thickness 0.15)
				)
			)
		)
		(property "License" "Apache-2.0"
			(at 202.336501 50.215499 0)
			(layer "F.Fab")
			(hide yes)
			(effects
				(font
					(size 1 1)
					(thickness 0.15)
				)
			)
		)
		(property "MPN" "1296.2013"
			(at 202.336501 50.215499 0)
			(layer "F.Fab")
			(hide yes)
			(effects
				(font
					(size 1 1)
					(thickness 0.15)
				)
			)
		)
		(property "Manufacturer" "Mentor Worldwide"
			(at 202.336501 50.215499 0)
			(layer "F.Fab")
			(hide yes)
			(effects
				(font
					(size 1 1)
					(thickness 0.15)
				)
			)
		)
		(sheetname "/")
		(sheetfile "sodimm-ddr5-tester.kicad_sch")
		(fp_rect
			(start -1.508 -6.335)
			(end 1.507 5.289)
			(stroke
				(width 0.15)
				(type solid)
			)
			(fill no)
			(layer "F.SilkS")
		)
		(pad "" np_thru_hole circle
			(at 0 -4.96 90)
			(size 1.2 1.2)
			(drill 1.2)
			(layers "*.Cu" "*.Mask")
		)
		(pad "" np_thru_hole circle
			(at 0 4.24 90)
			(size 1.2 1.2)
			(drill 1.2)
			(layers "*.Cu" "*.Mask")
		)
	)
	(footprint "antmicro-footprints:R_0402_1005Metric"
		(layer "F.Cu")
		(at 77.7 157.5)
		(descr "Resistor SMD 0402")
		(tags "resistor SMD 0402")
		(property "Reference" "R69"
			(at -1.122484 -0.772697 0)
			(layer "F.SilkS")
			(hide yes)
			(effects
				(font
					(size 0.7 0.7)
					(thickness 0.15)
				)
				(justify left bottom)
			)
		)
		(property "Value" "R_5k11_0402"
			(at -1.011843 1.772047 0)
			(layer "F.Fab")
			(effects
				(font
					(size 0.7 0.7)
					(thickness 0.15)
				)
				(justify left bottom)
			)
		)
		(property "Datasheet" "https://www.bourns.com/docs/product-datasheets/cr.pdf"
			(at 0 0 0)
			(layer "F.Fab")
			(hide yes)
			(effects
				(font
					(size 1.27 1.27)
					(thickness 0.15)
				)
			)
		)
		(property "Author" "Antmicro"
			(at 0 0 0)
			(layer "F.Fab")
			(hide yes)
			(effects
				(font
					(size 1 1)
					(thickness 0.15)
				)
			)
		)
		(property "License" "Apache-2.0"
			(at 0 0 0)
			(layer "F.Fab")
			(hide yes)
			(effects
				(font
					(size 1 1)
					(thickness 0.15)
				)
			)
		)
		(property "MPN" "CR0402-FX-5111GLF"
			(at 0 0 0)
			(layer "F.Fab")
			(hide yes)
			(effects
				(font
					(size 1 1)
					(thickness 0.15)
				)
			)
		)
		(property "Manufacturer" "Bourns"
			(at 0 0 0)
			(layer "F.Fab")
			(hide yes)
			(effects
				(font
					(size 1 1)
					(thickness 0.15)
				)
			)
		)
		(property "Tolerance" "1%"
			(at 0 0 0)
			(layer "F.Fab")
			(hide yes)
			(effects
				(font
					(size 1 1)
					(thickness 0.15)
				)
			)
		)
		(property "Val" "5k11"
			(at 0 0 0)
			(layer "F.Fab")
			(hide yes)
			(effects
				(font
					(size 1 1)
					(thickness 0.15)
				)
			)
		)
		(sheetname "/Debug FTDI/")
		(sheetfile "debug-ftdi.kicad_sch")
		(attr smd)
		(fp_rect
			(start -0.93 -0.47)
			(end 0.93 0.47)
			(stroke
				(width 0.05)
				(type solid)
			)
			(fill no)
			(layer "F.CrtYd")
		)
		(fp_rect
			(start -0.5 -0.25)
			(end 0.5 0.25)
			(stroke
				(width 0.15)
				(type solid)
			)
			(fill no)
			(layer "F.Fab")
		)
		(pad "1" smd roundrect
			(at -0.485 0)
			(size 0.59 0.64)
			(layers "F.Cu" "F.Mask" "F.Paste")
			(roundrect_rratio 0.25)
			(net 323 "Net-(J3-CC_{2})")
			(pintype "passive")
		)
		(pad "2" smd roundrect
			(at 0.485 0)
			(size 0.59 0.64)
			(layers "F.Cu" "F.Mask" "F.Paste")
			(roundrect_rratio 0.25)
			(net 1 "GND")
			(pintype "passive")
		)
	)
	(footprint "antmicro-footprints:R_1206_3216Metric"
		(layer "F.Cu")
		(at 199.051501 159.699 180)
		(property "Reference" "R147"
			(at 5.101501 -1.001 180)
			(layer "F.SilkS")
			(effects
				(font
					(size 0.7 0.7)
					(thickness 0.15)
				)
				(justify left bottom)
			)
		)
		(property "Value" "R_0R01_1206"
			(at -2.422356 2.103591 180)
			(layer "F.Fab")
			(effects
				(font
					(size 0.7 0.7)
					(thickness 0.15)
				)
				(justify left bottom)
			)
		)
		(property "Datasheet" "https://www.yageo.com/upload/media/product/productsearch/datasheet/rchip/PYu-RL_Group_521_RoHS_L_2.pdf"
			(at 0 0 180)
			(layer "F.Fab")
			(hide yes)
			(effects
				(font
					(size 1.27 1.27)
					(thickness 0.15)
				)
			)
		)
		(property "Author" "Antmicro"
			(at 398.103002 319.398 0)
			(layer "F.Fab")
			(hide yes)
			(effects
				(font
					(size 1 1)
					(thickness 0.15)
				)
			)
		)
		(property "License" "Apache-2.0"
			(at 398.103002 319.398 0)
			(layer "F.Fab")
			(hide yes)
			(effects
				(font
					(size 1 1)
					(thickness 0.15)
				)
			)
		)
		(property "MPN" "RL1206FR-7W0R01L"
			(at 398.103002 319.398 0)
			(layer "F.Fab")
			(hide yes)
			(effects
				(font
					(size 1 1)
					(thickness 0.15)
				)
			)
		)
		(property "Manufacturer" "YAGEO"
			(at 398.103002 319.398 0)
			(layer "F.Fab")
			(hide yes)
			(effects
				(font
					(size 1 1)
					(thickness 0.15)
				)
			)
		)
		(property "Tolerance" "1%"
			(at 398.103002 319.398 0)
			(layer "F.Fab")
			(hide yes)
			(effects
				(font
					(size 1 1)
					(thickness 0.15)
				)
			)
		)
		(property "Val" "0R01"
			(at 398.103002 319.398 0)
			(layer "F.Fab")
			(hide yes)
			(effects
				(font
					(size 1 1)
					(thickness 0.15)
				)
			)
		)
		(sheetname "/Supply/")
		(sheetfile "supply.kicad_sch")
		(attr smd)
		(fp_line
			(start 0 0.9)
			(end 0.498 0.9)
			(stroke
				(width 0.15)
				(type solid)
			)
			(layer "F.SilkS")
		)
		(fp_line
			(start 0 0.9)
			(end -0.5 0.9)
			(stroke
				(width 0.15)
				(type solid)
			)
			(layer "F.SilkS")
		)
		(fp_line
			(start 0 -0.902)
			(end 0.498 -0.902)
			(stroke
				(width 0.15)
				(type solid)
			)
			(layer "F.SilkS")
		)
		(fp_line
			(start 0 -0.902)
			(end -0.5 -0.902)
			(stroke
				(width 0.15)
				(type solid)
			)
			(layer "F.SilkS")
		)
		(fp_rect
			(start -2.25 -1.05)
			(end 2.25 1.05)
			(stroke
				(width 0.05)
				(type solid)
			)
			(fill no)
			(layer "F.CrtYd")
		)
		(fp_line
			(start 1.6 -0.802)
			(end 1.6 0.8)
			(stroke
				(width 0.15)
				(type solid)
			)
			(layer "F.Fab")
		)
		(fp_line
			(start -1.601 0.8)
			(end 1.6 0.8)
			(stroke
				(width 0.15)
				(type solid)
			)
			(layer "F.Fab")
		)
		(fp_line
			(start -1.601 -0.802)
			(end 1.6 -0.802)
			(stroke
				(width 0.15)
				(type solid)
			)
			(layer "F.Fab")
		)
		(fp_line
			(start -1.601 -0.802)
			(end -1.601 0.8)
			(stroke
				(width 0.15)
				(type solid)
			)
			(layer "F.Fab")
		)
		(pad "1" smd roundrect
			(at -1.5 0 180)
			(size 1.2 1.8)
			(layers "F.Cu" "F.Mask" "F.Paste")
			(roundrect_rratio 0.15)
			(net 53 "/Supply/1V1_local")
			(pintype "passive")
		)
		(pad "2" smd roundrect
			(at 1.499 0 180)
			(size 1.2 1.8)
			(layers "F.Cu" "F.Mask" "F.Paste")
			(roundrect_rratio 0.15)
			(net 206 "+1V1")
			(pintype "passive")
		)
	)
	(footprint "antmicro-footprints:C_0402_1005Metric"
		(layer "F.Cu")
		(at 195.15 193.075)
		(descr "Capacitor SMD 0402")
		(tags "capacitor SMD 0402")
		(property "Reference" "C206"
			(at 0 -0.699 0)
			(layer "F.SilkS")
			(hide yes)
			(effects
				(font
					(size 0.7 0.7)
					(thickness 0.15)
				)
				(justify left bottom)
			)
		)
		(property "Value" "C_1u_0402"
			(at -1.022927 2.155213 0)
			(layer "F.Fab")
			(effects
				(font
					(size 0.7 0.7)
					(thickness 0.15)
				)
				(justify left bottom)
			)
		)
		(property "Datasheet" "https://product.tdk.com/en/search/capacitor/ceramic/mlcc/info?part_no=C1005X6S1A105K050BC"
			(at 0 0 0)
			(layer "F.Fab")
			(hide yes)
			(effects
				(font
					(size 1.27 1.27)
					(thickness 0.15)
				)
			)
		)
		(property "Author" "Antmicro"
			(at 0 0 0)
			(layer "F.Fab")
			(hide yes)
			(effects
				(font
					(size 1 1)
					(thickness 0.15)
				)
			)
		)
		(property "Dielectric" ""
			(at 0 0 0)
			(layer "F.Fab")
			(hide yes)
			(effects
				(font
					(size 1 1)
					(thickness 0.15)
				)
			)
		)
		(property "License" "Apache-2.0"
			(at 0 0 0)
			(layer "F.Fab")
			(hide yes)
			(effects
				(font
					(size 1 1)
					(thickness 0.15)
				)
			)
		)
		(property "MPN" "C1005X6S1A105K050BC"
			(at 0 0 0)
			(layer "F.Fab")
			(hide yes)
			(effects
				(font
					(size 1 1)
					(thickness 0.15)
				)
			)
		)
		(property "Manufacturer" "TDK"
			(at 0 0 0)
			(layer "F.Fab")
			(hide yes)
			(effects
				(font
					(size 1 1)
					(thickness 0.15)
				)
			)
		)
		(property "Val" "1u"
			(at 0 0 0)
			(layer "F.Fab")
			(hide yes)
			(effects
				(font
					(size 1 1)
					(thickness 0.15)
				)
			)
		)
		(property "Voltage" ""
			(at 0 0 0)
			(layer "F.Fab")
			(hide yes)
			(effects
				(font
					(size 1 1)
					(thickness 0.15)
				)
			)
		)
		(sheetname "/Supply/")
		(sheetfile "supply.kicad_sch")
		(attr smd)
		(fp_rect
			(start -0.9659 -0.481258)
			(end 0.9649 0.458742)
			(stroke
				(width 0.05)
				(type solid)
			)
			(fill no)
			(layer "F.CrtYd")
		)
		(fp_line
			(start -0.499 -0.25)
			(end 0.499 -0.25)
			(stroke
				(width 0.15)
				(type solid)
			)
			(layer "F.Fab")
		)
		(fp_line
			(start -0.499 0.248)
			(end -0.499 -0.25)
			(stroke
				(width 0.15)
				(type solid)
			)
			(layer "F.Fab")
		)
		(fp_line
			(start 0.499 -0.25)
			(end 0.499 0.248)
			(stroke
				(width 0.15)
				(type solid)
			)
			(layer "F.Fab")
		)
		(fp_line
			(start 0.499 0.248)
			(end -0.499 0.248)
			(stroke
				(width 0.15)
				(type solid)
			)
			(layer "F.Fab")
		)
		(pad "1" smd roundrect
			(at -0.484 0)
			(size 0.59 0.64)
			(layers "F.Cu" "F.Mask" "F.Paste")
			(roundrect_rratio 0.25)
			(net 1 "GND")
			(pintype "passive")
		)
		(pad "2" smd roundrect
			(at 0.484 0)
			(size 0.59 0.64)
			(layers "F.Cu" "F.Mask" "F.Paste")
			(roundrect_rratio 0.25)
			(net 64 "/Supply/1V7")
			(pintype "passive")
		)
	)
	(footprint "antmicro-footprints:C_0603_1608Metric"
		(layer "F.Cu")
		(at 192.668501 165.472 90)
		(descr "Capacitor SMD 0603")
		(tags "capacitor 0603")
		(property "Reference" "C185"
			(at -1.42757 -1.000252 90)
			(layer "F.SilkS")
			(hide yes)
			(effects
				(font
					(size 0.7 0.7)
					(thickness 0.15)
				)
				(justify left bottom)
			)
		)
		(property "Value" "C_22u_0603"
			(at -1.42757 1.770288 90)
			(layer "F.Fab")
			(effects
				(font
					(size 0.7 0.7)
					(thickness 0.15)
				)
				(justify left bottom)
			)
		)
		(property "Datasheet" "https://www.murata.com/products/productdetail?partno=GRM188R60J226MEA0%23"
			(at 0 0 90)
			(layer "F.Fab")
			(hide yes)
			(effects
				(font
					(size 1.27 1.27)
					(thickness 0.15)
				)
			)
		)
		(property "Author" "Antmicro"
			(at 358.140501 -27.196501 0)
			(layer "F.Fab")
			(hide yes)
			(effects
				(font
					(size 1 1)
					(thickness 0.15)
				)
			)
		)
		(property "Dielectric" ""
			(at 358.140501 -27.196501 0)
			(layer "F.Fab")
			(hide yes)
			(effects
				(font
					(size 1 1)
					(thickness 0.15)
				)
			)
		)
		(property "License" "Apache-2.0"
			(at 358.140501 -27.196501 0)
			(layer "F.Fab")
			(hide yes)
			(effects
				(font
					(size 1 1)
					(thickness 0.15)
				)
			)
		)
		(property "MPN" "GRM188R60J226MEA0D"
			(at 358.140501 -27.196501 0)
			(layer "F.Fab")
			(hide yes)
			(effects
				(font
					(size 1 1)
					(thickness 0.15)
				)
			)
		)
		(property "Manufacturer" "Murata"
			(at 358.140501 -27.196501 0)
			(layer "F.Fab")
			(hide yes)
			(effects
				(font
					(size 1 1)
					(thickness 0.15)
				)
			)
		)
		(property "Val" "22u"
			(at 358.140501 -27.196501 0)
			(layer "F.Fab")
			(hide yes)
			(effects
				(font
					(size 1 1)
					(thickness 0.15)
				)
			)
		)
		(property "Voltage" ""
			(at 358.140501 -27.196501 0)
			(layer "F.Fab")
			(hide yes)
			(effects
				(font
					(size 1 1)
					(thickness 0.15)
				)
			)
		)
		(sheetname "/Supply/")
		(sheetfile "supply.kicad_sch")
		(attr smd)
		(fp_line
			(start -0.3 -0.3)
			(end 0.3 -0.3)
			(stroke
				(width 0.15)
				(type solid)
			)
			(layer "F.SilkS")
		)
		(fp_line
			(start -0.3 0.3)
			(end 0.3 0.3)
			(stroke
				(width 0.15)
				(type solid)
			)
			(layer "F.SilkS")
		)
		(fp_rect
			(start -1.24 -0.7)
			(end 1.24 0.7)
			(stroke
				(width 0.05)
				(type solid)
			)
			(fill no)
			(layer "F.CrtYd")
		)
		(fp_rect
			(start -0.8 -0.4)
			(end 0.8 0.4)
			(stroke
				(width 0.15)
				(type solid)
			)
			(fill no)
			(layer "F.Fab")
		)
		(pad "1" smd roundrect
			(at -0.7 0 90)
			(size 0.6 0.8)
			(layers "F.Cu" "F.Mask" "F.Paste")
			(roundrect_rratio 0.2)
			(net 1 "GND")
			(pintype "passive")
		)
		(pad "2" smd roundrect
			(at 0.7 0 90)
			(size 0.6 0.8)
			(layers "F.Cu" "F.Mask" "F.Paste")
			(roundrect_rratio 0.2)
			(net 60 "/Supply/5V_local")
			(pintype "passive")
		)
	)
	(footprint "antmicro-footprints:R_0402_1005Metric"
		(layer "F.Cu")
		(at 180.915 128.2)
		(descr "Resistor SMD 0402")
		(tags "resistor SMD 0402")
		(property "Reference" "R78"
			(at -1.122484 -0.772697 0)
			(layer "F.SilkS")
			(hide yes)
			(effects
				(font
					(size 0.7 0.7)
					(thickness 0.15)
				)
				(justify left bottom)
			)
		)
		(property "Value" "R_4k7_0402"
			(at -1.011843 1.772047 0)
			(layer "F.Fab")
			(effects
				(font
					(size 0.7 0.7)
					(thickness 0.15)
				)
				(justify left bottom)
			)
		)
		(property "Datasheet" "https://www.bourns.com/docs/product-datasheets/cr.pdf"
			(at 0 0 0)
			(layer "F.Fab")
			(hide yes)
			(effects
				(font
					(size 1.27 1.27)
					(thickness 0.15)
				)
			)
		)
		(property "Author" "Antmicro"
			(at 0 0 0)
			(layer "F.Fab")
			(hide yes)
			(effects
				(font
					(size 1 1)
					(thickness 0.15)
				)
			)
		)
		(property "License" "Apache-2.0"
			(at 0 0 0)
			(layer "F.Fab")
			(hide yes)
			(effects
				(font
					(size 1 1)
					(thickness 0.15)
				)
			)
		)
		(property "MPN" "CR0402-FX-4701GLF"
			(at 0 0 0)
			(layer "F.Fab")
			(hide yes)
			(effects
				(font
					(size 1 1)
					(thickness 0.15)
				)
			)
		)
		(property "Manufacturer" "Bourns"
			(at 0 0 0)
			(layer "F.Fab")
			(hide yes)
			(effects
				(font
					(size 1 1)
					(thickness 0.15)
				)
			)
		)
		(property "Tolerance" "1%"
			(at 0 0 0)
			(layer "F.Fab")
			(hide yes)
			(effects
				(font
					(size 1 1)
					(thickness 0.15)
				)
			)
		)
		(property "Val" "4k7"
			(at 0 0 0)
			(layer "F.Fab")
			(hide yes)
			(effects
				(font
					(size 1 1)
					(thickness 0.15)
				)
			)
		)
		(sheetname "/DDR5 SODIMM/")
		(sheetfile "ddr5-sodimm.kicad_sch")
		(attr smd)
		(fp_rect
			(start -0.93 -0.47)
			(end 0.93 0.47)
			(stroke
				(width 0.05)
				(type solid)
			)
			(fill no)
			(layer "F.CrtYd")
		)
		(fp_rect
			(start -0.5 -0.25)
			(end 0.5 0.25)
			(stroke
				(width 0.15)
				(type solid)
			)
			(fill no)
			(layer "F.Fab")
		)
		(pad "1" smd roundrect
			(at -0.485 0)
			(size 0.59 0.64)
			(layers "F.Cu" "F.Mask" "F.Paste")
			(roundrect_rratio 0.25)
			(net 200 "+3V3")
			(pintype "passive")
		)
		(pad "2" smd roundrect
			(at 0.485 0)
			(size 0.59 0.64)
			(layers "F.Cu" "F.Mask" "F.Paste")
			(roundrect_rratio 0.25)
			(net 106 "HOT_SWAP_BUTTON")
			(pintype "passive")
		)
	)
)
